(kicad_pcb
	(version 20241229)
	(generator "pcbnew")
	(generator_version "9.0")
	(general
		(thickness 1.294)
		(legacy_teardrops no)
	)
	(paper "A3")
	(title_block
		(title "Kintex 410T devboard")
		(date "2024-04-03")
		(rev "1.1.2")
		(comment 9 "footprints 502-506 of 975")
	)
	(layers
		(0 "F.Cu" mixed)
		(4 "In1.Cu" power)
		(6 "In2.Cu" power)
		(8 "In3.Cu" mixed)
		(10 "In4.Cu" power)
		(12 "In5.Cu" mixed)
		(14 "In6.Cu" power)
		(16 "In7.Cu" mixed)
		(18 "In8.Cu" power)
		(2 "B.Cu" mixed)
		(9 "F.Adhes" user "F.Adhesive")
		(11 "B.Adhes" user "B.Adhesive")
		(13 "F.Paste" user)
		(15 "B.Paste" user)
		(5 "F.SilkS" user "F.Silkscreen")
		(7 "B.SilkS" user "B.Silkscreen")
		(1 "F.Mask" user)
		(3 "B.Mask" user)
		(17 "Dwgs.User" user "User.Drawings")
		(19 "Cmts.User" user "User.Comments")
		(21 "Eco1.User" user "User.Eco1")
		(23 "Eco2.User" user "User.Eco2")
		(25 "Edge.Cuts" user)
		(27 "Margin" user)
		(31 "F.CrtYd" user "F.Courtyard")
		(29 "B.CrtYd" user "B.Courtyard")
		(35 "F.Fab" user)
		(33 "B.Fab" user)
	)
	(footprint "antmicro-footprints:R_0402_1005Metric"
		(layer "B.Cu")
		(at 268.001 126.7)
		(descr "Resistor SMD 0402")
		(tags "resistor SMD 0402")
		(property "Reference" "R253"
			(at 1.724 -0.55 180)
			(layer "B.SilkS")
			(effects
				(font
					(size 0.7 0.7)
					(thickness 0.15)
				)
				(justify left bottom mirror)
			)
		)
		(property "Value" "R_100R_0402"
			(at 0 -1.4 180)
			(layer "B.Fab")
			(effects
				(font
					(size 0.7 0.7)
					(thickness 0.15)
				)
				(justify left bottom mirror)
			)
		)
		(property "Description" "SMD Chip Resistor, 100 ohm, ± 1%, 62.5 mW, 0402 [1005 Metric], Thick Film, General Purpose"
			(at 0 0 0)
			(layer "F.Fab")
			(hide yes)
			(effects
				(font
					(size 1.27 1.27)
					(thickness 0.15)
				)
			)
		)
		(property "Author" "Antmicro"
			(at 0 0 0)
			(layer "B.Fab")
			(hide yes)
			(effects
				(font
					(size 1 1)
					(thickness 0.15)
				)
				(justify mirror)
			)
		)
		(property "License" "Apache-2.0"
			(at 0 0 0)
			(layer "B.Fab")
			(hide yes)
			(effects
				(font
					(size 1 1)
					(thickness 0.15)
				)
				(justify mirror)
			)
		)
		(property "MPN" "CR0402-FX-1000GLF"
			(at 0 0 0)
			(layer "B.Fab")
			(hide yes)
			(effects
				(font
					(size 1 1)
					(thickness 0.15)
				)
				(justify mirror)
			)
		)
		(property "Manufacturer" "Bourns"
			(at 0 0 0)
			(layer "B.Fab")
			(hide yes)
			(effects
				(font
					(size 1 1)
					(thickness 0.15)
				)
				(justify mirror)
			)
		)
		(property "Tolerance" "1%"
			(at 0 0 0)
			(layer "B.Fab")
			(hide yes)
			(effects
				(font
					(size 1 1)
					(thickness 0.15)
				)
				(justify mirror)
			)
		)
		(property "Val" "100R"
			(at 0 0 0)
			(layer "B.Fab")
			(hide yes)
			(effects
				(font
					(size 1 1)
					(thickness 0.15)
				)
				(justify mirror)
			)
		)
		(sheetname "SPI Flash + SD Card")
		(sheetfile "spi-flash.kicad_sch")
		(attr smd)
		(fp_rect
			(start -0.925 0.47)
			(end 0.925 -0.47)
			(stroke
				(width 0.05)
				(type default)
			)
			(fill no)
			(layer "B.CrtYd")
		)
		(fp_rect
			(start -0.5 0.25)
			(end 0.5 -0.25)
			(stroke
				(width 0.15)
				(type solid)
			)
			(fill no)
			(layer "B.Fab")
		)
		(pad "1" smd roundrect
			(at -0.48 0)
			(size 0.59 0.64)
			(layers "B.Cu" "B.Mask" "B.Paste")
			(roundrect_rratio 0.25)
			(net 1 "GND")
			(pintype "passive")
		)
		(pad "2" smd roundrect
			(at 0.48 0)
			(size 0.59 0.64)
			(layers "B.Cu" "B.Mask" "B.Paste")
			(roundrect_rratio 0.25)
			(net 16 "Net-(J23-SHIELD)")
			(pintype "passive")
		)
	)
	(footprint "antmicro-footprints:C_0402_1005Metric"
		(layer "B.Cu")
		(at 174.5 173.7625 -90)
		(descr "Capacitor SMD 0402")
		(tags "capacitor SMD 0402")
		(property "Reference" "C318"
			(at -1.4375 -1.25 90)
			(layer "B.SilkS")
			(effects
				(font
					(size 0.7 0.7)
					(thickness 0.15)
				)
				(justify left bottom mirror)
			)
		)
		(property "Value" "C_1u_0402"
			(at 0 -1.4 90)
			(layer "B.Fab")
			(effects
				(font
					(size 0.7 0.7)
					(thickness 0.15)
				)
				(justify left bottom mirror)
			)
		)
		(property "Description" "SMD Multilayer Ceramic Capacitor, 1 µF, 10 V, 0402 [1005 Metric], ± 10%, X6S, C"
			(at 0 0 270)
			(layer "F.Fab")
			(hide yes)
			(effects
				(font
					(size 1.27 1.27)
					(thickness 0.15)
				)
			)
		)
		(property "Author" "Antmicro"
			(at 0.7375 348.2625 0)
			(layer "B.Fab")
			(hide yes)
			(effects
				(font
					(size 1 1)
					(thickness 0.15)
				)
				(justify mirror)
			)
		)
		(property "Dielectric" ""
			(at 0.7375 348.2625 0)
			(layer "B.Fab")
			(hide yes)
			(effects
				(font
					(size 1 1)
					(thickness 0.15)
				)
				(justify mirror)
			)
		)
		(property "License" "Apache-2.0"
			(at 0.7375 348.2625 0)
			(layer "B.Fab")
			(hide yes)
			(effects
				(font
					(size 1 1)
					(thickness 0.15)
				)
				(justify mirror)
			)
		)
		(property "MPN" "C1005X6S1A105K050BC"
			(at 0.7375 348.2625 0)
			(layer "B.Fab")
			(hide yes)
			(effects
				(font
					(size 1 1)
					(thickness 0.15)
				)
				(justify mirror)
			)
		)
		(property "Manufacturer" "TDK"
			(at 0.7375 348.2625 0)
			(layer "B.Fab")
			(hide yes)
			(effects
				(font
					(size 1 1)
					(thickness 0.15)
				)
				(justify mirror)
			)
		)
		(property "Val" "1u"
			(at 0.7375 348.2625 0)
			(layer "B.Fab")
			(hide yes)
			(effects
				(font
					(size 1 1)
					(thickness 0.15)
				)
				(justify mirror)
			)
		)
		(property "Voltage" ""
			(at 0.7375 348.2625 0)
			(layer "B.Fab")
			(hide yes)
			(effects
				(font
					(size 1 1)
					(thickness 0.15)
				)
				(justify mirror)
			)
		)
		(sheetname "DC-DC Converters")
		(sheetfile "dc-dc.kicad_sch")
		(attr smd)
		(fp_rect
			(start -0.925 0.47)
			(end 0.925 -0.47)
			(stroke
				(width 0.05)
				(type default)
			)
			(fill no)
			(layer "B.CrtYd")
		)
		(fp_line
			(start -0.494 0.25)
			(end 0.504 0.25)
			(stroke
				(width 0.15)
				(type solid)
			)
			(layer "B.Fab")
		)
		(fp_line
			(start 0.504 0.25)
			(end 0.504 -0.248)
			(stroke
				(width 0.15)
				(type solid)
			)
			(layer "B.Fab")
		)
		(fp_line
			(start -0.494 -0.248)
			(end -0.494 0.25)
			(stroke
				(width 0.15)
				(type solid)
			)
			(layer "B.Fab")
		)
		(fp_line
			(start 0.504 -0.248)
			(end -0.494 -0.248)
			(stroke
				(width 0.15)
				(type solid)
			)
			(layer "B.Fab")
		)
		(pad "1" smd roundrect
			(at -0.48 0 270)
			(size 0.59 0.64)
			(layers "B.Cu" "B.Mask" "B.Paste")
			(roundrect_rratio 0.25)
			(net 1 "GND")
			(pintype "passive")
		)
		(pad "2" smd roundrect
			(at 0.48 0 270)
			(size 0.59 0.64)
			(layers "B.Cu" "B.Mask" "B.Paste")
			(roundrect_rratio 0.25)
			(net 732 "/DC-DC Converters/QDCDC2_VCC")
			(pintype "passive")
		)
	)
	(footprint "antmicro-footprints:C_0402_1005Metric"
		(layer "B.Cu")
		(at 169.5 143.2 90)
		(descr "Capacitor SMD 0402")
		(tags "capacitor SMD 0402")
		(property "Reference" "C392"
			(at 1.075 2.35 270)
			(layer "B.SilkS")
			(effects
				(font
					(size 0.7 0.7)
					(thickness 0.15)
				)
				(justify left bottom mirror)
			)
		)
		(property "Value" "C_100n_0402"
			(at 0 -1.169 270)
			(layer "B.Fab")
			(effects
				(font
					(size 0.7 0.7)
					(thickness 0.15)
				)
				(justify left bottom mirror)
			)
		)
		(property "Description" "SMD Multilayer Ceramic Capacitor, 0.1 µF, 50 V, 0402 [1005 Metric], ± 10%, X5R, GRM Series"
			(at 0 0 90)
			(layer "F.Fab")
			(hide yes)
			(effects
				(font
					(size 1.27 1.27)
					(thickness 0.15)
				)
			)
		)
		(property "Author" "Antmicro"
			(at 312.7 -26.3 0)
			(layer "B.Fab")
			(hide yes)
			(effects
				(font
					(size 1 1)
					(thickness 0.15)
				)
				(justify mirror)
			)
		)
		(property "Dielectric" "X5R"
			(at 312.7 -26.3 0)
			(layer "B.Fab")
			(hide yes)
			(effects
				(font
					(size 1 1)
					(thickness 0.15)
				)
				(justify mirror)
			)
		)
		(property "License" "Apache-2.0"
			(at 312.7 -26.3 0)
			(layer "B.Fab")
			(hide yes)
			(effects
				(font
					(size 1 1)
					(thickness 0.15)
				)
				(justify mirror)
			)
		)
		(property "MPN" "GRM155R61H104KE14D"
			(at 312.7 -26.3 0)
			(layer "B.Fab")
			(hide yes)
			(effects
				(font
					(size 1 1)
					(thickness 0.15)
				)
				(justify mirror)
			)
		)
		(property "Manufacturer" "Murata"
			(at 312.7 -26.3 0)
			(layer "B.Fab")
			(hide yes)
			(effects
				(font
					(size 1 1)
					(thickness 0.15)
				)
				(justify mirror)
			)
		)
		(property "Val" "100n"
			(at 312.7 -26.3 0)
			(layer "B.Fab")
			(hide yes)
			(effects
				(font
					(size 1 1)
					(thickness 0.15)
				)
				(justify mirror)
			)
		)
		(property "Voltage" "50V"
			(at 312.7 -26.3 0)
			(layer "B.Fab")
			(hide yes)
			(effects
				(font
					(size 1 1)
					(thickness 0.15)
				)
				(justify mirror)
			)
		)
		(sheetname "DRAM + SRAM")
		(sheetfile "ram.kicad_sch")
		(attr smd)
		(fp_rect
			(start -0.925 0.47)
			(end 0.925 -0.47)
			(stroke
				(width 0.05)
				(type default)
			)
			(fill no)
			(layer "B.CrtYd")
		)
		(fp_line
			(start 0.504 -0.248)
			(end -0.494 -0.248)
			(stroke
				(width 0.15)
				(type solid)
			)
			(layer "B.Fab")
		)
		(fp_line
			(start -0.494 -0.248)
			(end -0.494 0.25)
			(stroke
				(width 0.15)
				(type solid)
			)
			(layer "B.Fab")
		)
		(fp_line
			(start 0.504 0.25)
			(end 0.504 -0.248)
			(stroke
				(width 0.15)
				(type solid)
			)
			(layer "B.Fab")
		)
		(fp_line
			(start -0.494 0.25)
			(end 0.504 0.25)
			(stroke
				(width 0.15)
				(type solid)
			)
			(layer "B.Fab")
		)
		(pad "1" smd roundrect
			(at -0.48 0 90)
			(size 0.59 0.64)
			(layers "B.Cu" "B.Mask" "B.Paste")
			(roundrect_rratio 0.25)
			(net 1 "GND")
			(pintype "passive")
		)
		(pad "2" smd roundrect
			(at 0.48 0 90)
			(size 0.59 0.64)
			(layers "B.Cu" "B.Mask" "B.Paste")
			(roundrect_rratio 0.25)
			(net 25 "+1V35")
			(pintype "passive")
		)
	)
	(footprint "antmicro-footprints:USON-10_2.5x1mm_P0.5mm"
		(layer "B.Cu")
		(at 253.751 110.3 90)
		(descr "USON-10 2.5x1mm_ Pitch 0.5mm")
		(tags "USON-10 2.5x1mm Pitch 0.5mm")
		(property "Reference" "U29"
			(at 0.8 1.074 0)
			(layer "B.SilkS")
			(effects
				(font
					(size 0.7 0.7)
					(thickness 0.15)
				)
				(justify left bottom mirror)
			)
		)
		(property "Value" "TPD4E05U06QDQARQ1"
			(at 0.018 -2.499 270)
			(layer "B.Fab")
			(effects
				(font
					(size 0.7 0.7)
					(thickness 0.15)
				)
				(justify left bottom mirror)
			)
		)
		(property "Description" "ESD protection"
			(at 0 0 90)
			(layer "F.Fab")
			(hide yes)
			(effects
				(font
					(size 1.27 1.27)
					(thickness 0.15)
				)
			)
		)
		(property "Author" "Antmicro"
			(at 364.051 -143.451 0)
			(layer "B.Fab")
			(hide yes)
			(effects
				(font
					(size 1 1)
					(thickness 0.15)
				)
				(justify mirror)
			)
		)
		(property "License" "Apache-2.0"
			(at 364.051 -143.451 0)
			(layer "B.Fab")
			(hide yes)
			(effects
				(font
					(size 1 1)
					(thickness 0.15)
				)
				(justify mirror)
			)
		)
		(property "MPN" "TPD4E05U06QDQARQ1"
			(at 364.051 -143.451 0)
			(layer "B.Fab")
			(hide yes)
			(effects
				(font
					(size 1 1)
					(thickness 0.15)
				)
				(justify mirror)
			)
		)
		(property "Manufacturer" "Texas Instruments"
			(at 364.051 -143.451 0)
			(layer "B.Fab")
			(hide yes)
			(effects
				(font
					(size 1 1)
					(thickness 0.15)
				)
				(justify mirror)
			)
		)
		(sheetname "HDMI + Ethernet")
		(sheetfile "hdmi-ethernet.kicad_sch")
		(attr smd)
		(fp_line
			(start 0.498 -1.398)
			(end -0.5 -1.398)
			(stroke
				(width 0.15)
				(type solid)
			)
			(layer "B.SilkS")
		)
		(fp_line
			(start 0.498 1.401)
			(end -0.5 1.401)
			(stroke
				(width 0.15)
				(type solid)
			)
			(layer "B.SilkS")
		)
		(fp_circle
			(center -0.68 1.27)
			(end -0.63 1.27)
			(stroke
				(width 0.15)
				(type solid)
			)
			(fill yes)
			(layer "B.SilkS")
		)
		(fp_rect
			(start -0.8 1.5)
			(end 0.8 -1.499)
			(stroke
				(width 0.05)
				(type solid)
			)
			(fill no)
			(layer "B.CrtYd")
		)
		(fp_line
			(start -0.5 -1.249)
			(end 0.498 -1.249)
			(stroke
				(width 0.15)
				(type solid)
			)
			(layer "B.Fab")
		)
		(fp_line
			(start -0.5 1)
			(end -0.5 -1.249)
			(stroke
				(width 0.15)
				(type solid)
			)
			(layer "B.Fab")
		)
		(fp_line
			(start 0.498 1.25)
			(end 0.498 -1.249)
			(stroke
				(width 0.15)
				(type solid)
			)
			(layer "B.Fab")
		)
		(fp_line
			(start 0.498 1.25)
			(end -0.25 1.25)
			(stroke
				(width 0.15)
				(type solid)
			)
			(layer "B.Fab")
		)
		(fp_line
			(start -0.25 1.25)
			(end -0.5 1)
			(stroke
				(width 0.15)
				(type solid)
			)
			(layer "B.Fab")
		)
		(pad "1" smd roundrect
			(at -0.387 1 180)
			(size 0.25 0.55)
			(layers "B.Cu" "B.Mask" "B.Paste")
			(roundrect_rratio 0.25)
			(net 863 "/HDMI + Ethernet/HDMI_CONN_D0_P")
			(pintype "passive")
		)
		(pad "2" smd roundrect
			(at -0.387 0.5 180)
			(size 0.25 0.55)
			(layers "B.Cu" "B.Mask" "B.Paste")
			(roundrect_rratio 0.25)
			(net 862 "/HDMI + Ethernet/HDMI_CONN_D0_N")
			(pintype "passive")
		)
		(pad "3" smd roundrect
			(at -0.387 0 180)
			(size 0.4 0.55)
			(layers "B.Cu" "B.Mask" "B.Paste")
			(roundrect_rratio 0.25)
			(net 1 "GND")
			(pintype "power_in")
		)
		(pad "4" smd roundrect
			(at -0.387 -0.498 180)
			(size 0.25 0.55)
			(layers "B.Cu" "B.Mask" "B.Paste")
			(roundrect_rratio 0.25)
			(net 861 "/HDMI + Ethernet/HDMI_CONN_CLK_P")
			(pintype "passive")
		)
		(pad "5" smd roundrect
			(at -0.387 -0.998 180)
			(size 0.25 0.55)
			(layers "B.Cu" "B.Mask" "B.Paste")
			(roundrect_rratio 0.25)
			(net 868 "/HDMI + Ethernet/HDMI_CONN_CLK_N")
			(pintype "passive")
		)
		(pad "6" smd roundrect
			(at 0.385 -0.998 180)
			(size 0.25 0.55)
			(layers "B.Cu" "B.Mask" "B.Paste")
			(roundrect_rratio 0.25)
			(net 868 "/HDMI + Ethernet/HDMI_CONN_CLK_N")
			(pintype "passive")
		)
		(pad "7" smd roundrect
			(at 0.385 -0.498 180)
			(size 0.25 0.55)
			(layers "B.Cu" "B.Mask" "B.Paste")
			(roundrect_rratio 0.25)
			(net 861 "/HDMI + Ethernet/HDMI_CONN_CLK_P")
			(pintype "passive")
		)
		(pad "8" smd roundrect
			(at 0.385 0 180)
			(size 0.4 0.55)
			(layers "B.Cu" "B.Mask" "B.Paste")
			(roundrect_rratio 0.25)
			(net 1 "GND")
			(pintype "passive")
		)
		(pad "9" smd roundrect
			(at 0.385 0.5 180)
			(size 0.25 0.55)
			(layers "B.Cu" "B.Mask" "B.Paste")
			(roundrect_rratio 0.25)
			(net 862 "/HDMI + Ethernet/HDMI_CONN_D0_N")
			(pintype "passive")
		)
		(pad "10" smd roundrect
			(at 0.385 1 180)
			(size 0.25 0.55)
			(layers "B.Cu" "B.Mask" "B.Paste")
			(roundrect_rratio 0.25)
			(net 863 "/HDMI + Ethernet/HDMI_CONN_D0_P")
			(pintype "passive")
		)
	)
	(footprint "antmicro-footprints:C_0201"
		(layer "B.Cu")
		(at 189.8 119.5 180)
		(descr "Capacitor SMD 0201")
		(tags "capacitor SMD 0201")
		(property "Reference" "C149"
			(at 0.55 -0.25 0)
			(layer "B.SilkS")
			(effects
				(font
					(size 0.7 0.7)
					(thickness 0.15)
				)
				(justify left bottom mirror)
			)
		)
		(property "Value" "C_100n_0201"
			(at 0 -1.4 0)
			(layer "B.Fab")
			(effects
				(font
					(size 0.7 0.7)
					(thickness 0.15)
				)
				(justify left bottom mirror)
			)
		)
		(property "Description" "SMD Multilayer Ceramic Capacitor, 0.1 µF, 6.3 V, 0201 [0603 Metric], ± 10%, X6S, CC Series"
			(at 0 0 180)
			(layer "F.Fab")
			(hide yes)
			(effects
				(font
					(size 1.27 1.27)
					(thickness 0.15)
				)
			)
		)
		(property "Author" "Antmicro"
			(at 379.6 239 0)
			(layer "B.Fab")
			(hide yes)
			(effects
				(font
					(size 1 1)
					(thickness 0.15)
				)
				(justify mirror)
			)
		)
		(property "Dielectric" ""
			(at 379.6 239 0)
			(layer "B.Fab")
			(hide yes)
			(effects
				(font
					(size 1 1)
					(thickness 0.15)
				)
				(justify mirror)
			)
		)
		(property "License" "Apache-2.0"
			(at 379.6 239 0)
			(layer "B.Fab")
			(hide yes)
			(effects
				(font
					(size 1 1)
					(thickness 0.15)
				)
				(justify mirror)
			)
		)
		(property "MPN" "CC0201KRX6S5BB104"
			(at 379.6 239 0)
			(layer "B.Fab")
			(hide yes)
			(effects
				(font
					(size 1 1)
					(thickness 0.15)
				)
				(justify mirror)
			)
		)
		(property "Manufacturer" "YAGEO"
			(at 379.6 239 0)
			(layer "B.Fab")
			(hide yes)
			(effects
				(font
					(size 1 1)
					(thickness 0.15)
				)
				(justify mirror)
			)
		)
		(property "Val" "100n"
			(at 379.6 239 0)
			(layer "B.Fab")
			(hide yes)
			(effects
				(font
					(size 1 1)
					(thickness 0.15)
				)
				(justify mirror)
			)
		)
		(property "Voltage" ""
			(at 379.6 239 0)
			(layer "B.Fab")
			(hide yes)
			(effects
				(font
					(size 1 1)
					(thickness 0.15)
				)
				(justify mirror)
			)
		)
		(sheetname "FPGA supply")
		(sheetfile "fpga-supply.kicad_sch")
		(attr smd)
		(fp_rect
			(start -0.7 0.35)
			(end 0.7 -0.35)
			(stroke
				(width 0.05)
				(type default)
			)
			(fill no)
			(layer "B.CrtYd")
		)
		(fp_rect
			(start 0.3 -0.15)
			(end -0.301 0.149)
			(stroke
				(width 0.15)
				(type solid)
			)
			(fill no)
			(layer "B.Fab")
		)
		(pad "" smd roundrect
			(at -0.349 0.002 180)
			(size 0.318 0.36)
			(layers "B.Paste")
			(roundrect_rratio 0.25)
		)
		(pad "" smd roundrect
			(at 0.341 0.002 180)
			(size 0.318 0.36)
			(layers "B.Paste")
			(roundrect_rratio 0.25)
		)
		(pad "1" smd roundrect
			(at -0.321 0.002 180)
			(size 0.46 0.4)
			(layers "B.Cu" "B.Mask")
			(roundrect_rratio 0.25)
			(net 1 "GND")
			(pintype "passive")
		)
		(pad "2" smd roundrect
			(at 0.32 0.002 180)
			(size 0.46 0.4)
			(layers "B.Cu" "B.Mask")
			(roundrect_rratio 0.25)
			(net 8 "+1V2_MGTAVTT")
			(pintype "passive")
		)
	)
)
